(kicad_pcb
	(version 20241229)
	(generator "pcbnew")
	(generator_version "9.0")
	(general
		(thickness 1.6642)
		(legacy_teardrops no)
	)
	(paper "A3")
	(title_block
		(title "PolarFire SoM")
		(date "2025-07-22")
		(rev "1.1.4")
		(company "Antmicro Ltd")
		(comment 1 "www.antmicro.com")
		(comment 9 "footprints 1-4 of 470")
	)
	(layers
		(0 "F.Cu" mixed)
		(4 "In1.Cu" power)
		(6 "In2.Cu" signal)
		(8 "In3.Cu" power)
		(10 "In4.Cu" signal)
		(12 "In5.Cu" power)
		(14 "In6.Cu" power)
		(16 "In7.Cu" signal)
		(18 "In8.Cu" power)
		(20 "In9.Cu" signal)
		(22 "In10.Cu" power)
		(24 "In11.Cu" signal)
		(26 "In12.Cu" signal)
		(2 "B.Cu" mixed)
		(9 "F.Adhes" user "F.Adhesive")
		(11 "B.Adhes" user "B.Adhesive")
		(13 "F.Paste" user)
		(15 "B.Paste" user)
		(5 "F.SilkS" user "F.Silkscreen")
		(7 "B.SilkS" user "B.Silkscreen")
		(1 "F.Mask" user)
		(3 "B.Mask" user)
		(17 "Dwgs.User" user "User.Drawings")
		(19 "Cmts.User" user "User.Comments")
		(21 "Eco1.User" user "User.Eco1")
		(23 "Eco2.User" user "User.Eco2")
		(25 "Edge.Cuts" user)
		(27 "Margin" user)
		(31 "F.CrtYd" user "F.Courtyard")
		(29 "B.CrtYd" user "B.Courtyard")
		(35 "F.Fab" user)
		(33 "B.Fab" user)
	)
	(footprint "antmicro-footprints:TP_SMD_0.75mm"
		(layer "F.Cu")
		(at 228.47 144.005)
		(property "Reference" "TP32"
			(at 9.76 0.755 180)
			(layer "F.SilkS")
			(hide yes)
			(effects
				(font
					(size 0.7 0.7)
					(thickness 0.15)
				)
				(justify left bottom)
			)
		)
		(property "Value" "TP_0.75mm_SMD"
			(at 0 1.2 0)
			(layer "F.Fab")
			(hide yes)
			(effects
				(font
					(size 0.7 0.7)
					(thickness 0.15)
				)
				(justify left bottom)
			)
		)
		(property "Description" "SMT test point"
			(at 0 0 0)
			(layer "F.Fab")
			(hide yes)
			(effects
				(font
					(size 1.27 1.27)
					(thickness 0.15)
				)
			)
		)
		(property "Author" "Antmicro"
			(at 0 0 0)
			(layer "F.Fab")
			(hide yes)
			(effects
				(font
					(size 1 1)
					(thickness 0.15)
				)
			)
		)
		(property "License" "Apache-2.0"
			(at 0 0 0)
			(layer "F.Fab")
			(hide yes)
			(effects
				(font
					(size 1 1)
					(thickness 0.15)
				)
			)
		)
		(property "MPN" ""
			(at 0 0 0)
			(layer "F.Fab")
			(hide yes)
			(effects
				(font
					(size 1 1)
					(thickness 0.15)
				)
			)
		)
		(property "Manufacturer" ""
			(at 0 0 0)
			(layer "F.Fab")
			(hide yes)
			(effects
				(font
					(size 1 1)
					(thickness 0.15)
				)
			)
		)
		(property "Public" "False"
			(at 0 0 0)
			(layer "F.Fab")
			(hide yes)
			(effects
				(font
					(size 1 1)
					(thickness 0.15)
				)
			)
		)
		(sheetname "/WiFi_Bluetooth/")
		(sheetfile "wifi_bt.kicad_sch")
		(attr exclude_from_pos_files exclude_from_bom)
		(fp_circle
			(center 0 0)
			(end 0.475 0)
			(stroke
				(width 0.05)
				(type default)
			)
			(fill no)
			(layer "F.CrtYd")
		)
		(fp_text user "${REFERENCE}"
			(at -0.4 2.7 0)
			(layer "F.Fab")
			(effects
				(font
					(size 0.7 0.7)
					(thickness 0.15)
				)
				(justify left bottom)
			)
		)
		(fp_text user "License: Apache-2.0"
			(at -0.4 5.101 0)
			(layer "F.Fab")
			(effects
				(font
					(size 0.7 0.7)
					(thickness 0.15)
				)
				(justify left bottom)
			)
		)
		(fp_text user "Author: Antmicro"
			(at -0.4 3.901 0)
			(layer "F.Fab")
			(effects
				(font
					(size 0.7 0.7)
					(thickness 0.15)
				)
				(justify left bottom)
			)
		)
		(pad "1" smd circle
			(at 0 0)
			(size 0.75 0.75)
			(layers "F.Cu" "F.Mask")
			(net 529 "Net-(U26A-BT_GPIO_5)")
			(pinfunction "1")
			(pintype "passive")
		)
	)
	(footprint "antmicro-footprints:C_0402_1005Metric"
		(layer "F.Cu")
		(at 192.15 120.95 90)
		(descr "Capacitor SMD 0402")
		(tags "capacitor SMD 0402")
		(property "Reference" "C132"
			(at -1.71 6.03 270)
			(layer "F.SilkS")
			(effects
				(font
					(size 0.7 0.7)
					(thickness 0.15)
				)
				(justify left bottom)
			)
		)
		(property "Value" "C_100n_0402"
			(at -1.022927 2.155213 90)
			(layer "F.Fab")
			(hide yes)
			(effects
				(font
					(size 0.7 0.7)
					(thickness 0.15)
				)
				(justify left bottom)
			)
		)
		(property "Datasheet" "https://www.murata.com/products/productdetail?partno=GRM155R61H104KE14%23"
			(at 0 0 90)
			(layer "F.Fab")
			(hide yes)
			(effects
				(font
					(size 1.27 1.27)
					(thickness 0.15)
				)
			)
		)
		(property "Description" "SMD Multilayer Ceramic Capacitor, 0.1 µF, 50 V, 0402 [1005 Metric], ± 10%, X5R, GRM Series"
			(at 0 0 90)
			(layer "F.Fab")
			(hide yes)
			(effects
				(font
					(size 1.27 1.27)
					(thickness 0.15)
				)
			)
		)
		(property "Author" "Antmicro"
			(at 313.1 -71.2 0)
			(layer "F.Fab")
			(hide yes)
			(effects
				(font
					(size 1 1)
					(thickness 0.15)
				)
			)
		)
		(property "Dielectric" "X5R"
			(at 313.1 -71.2 0)
			(layer "F.Fab")
			(hide yes)
			(effects
				(font
					(size 1 1)
					(thickness 0.15)
				)
			)
		)
		(property "License" "Apache-2.0"
			(at 313.1 -71.2 0)
			(layer "F.Fab")
			(hide yes)
			(effects
				(font
					(size 1 1)
					(thickness 0.15)
				)
			)
		)
		(property "MPN" "GRM155R61H104KE14D"
			(at 313.1 -71.2 0)
			(layer "F.Fab")
			(hide yes)
			(effects
				(font
					(size 1 1)
					(thickness 0.15)
				)
			)
		)
		(property "Manufacturer" "Murata"
			(at 313.1 -71.2 0)
			(layer "F.Fab")
			(hide yes)
			(effects
				(font
					(size 1 1)
					(thickness 0.15)
				)
			)
		)
		(property "Public" ""
			(at 313.1 -71.2 0)
			(layer "F.Fab")
			(hide yes)
			(effects
				(font
					(size 1 1)
					(thickness 0.15)
				)
			)
		)
		(property "Val" "100n"
			(at 313.1 -71.2 0)
			(layer "F.Fab")
			(hide yes)
			(effects
				(font
					(size 1 1)
					(thickness 0.15)
				)
			)
		)
		(property "Voltage" "50V"
			(at 313.1 -71.2 0)
			(layer "F.Fab")
			(hide yes)
			(effects
				(font
					(size 1 1)
					(thickness 0.15)
				)
			)
		)
		(sheetname "/FPGA GPIO/")
		(sheetfile "fpga-gpio.kicad_sch")
		(attr smd)
		(fp_rect
			(start -0.925 -0.47)
			(end 0.925 0.47)
			(stroke
				(width 0.05)
				(type default)
			)
			(fill no)
			(layer "F.CrtYd")
		)
		(fp_line
			(start 0.504 -0.25)
			(end 0.504 0.248)
			(stroke
				(width 0.15)
				(type solid)
			)
			(layer "F.Fab")
		)
		(fp_line
			(start -0.494 -0.25)
			(end 0.504 -0.25)
			(stroke
				(width 0.15)
				(type solid)
			)
			(layer "F.Fab")
		)
		(fp_line
			(start 0.504 0.248)
			(end -0.494 0.248)
			(stroke
				(width 0.15)
				(type solid)
			)
			(layer "F.Fab")
		)
		(fp_line
			(start -0.494 0.248)
			(end -0.494 -0.25)
			(stroke
				(width 0.15)
				(type solid)
			)
			(layer "F.Fab")
		)
		(fp_text user "Author: Antmicro"
			(at -0.939 3.399 90)
			(layer "F.Fab")
			(effects
				(font
					(size 0.7 0.7)
					(thickness 0.15)
				)
				(justify left bottom)
			)
		)
		(fp_text user "${REFERENCE}"
			(at -0.939 4.599 90)
			(layer "F.Fab")
			(effects
				(font
					(size 0.7 0.7)
					(thickness 0.15)
				)
				(justify left bottom)
			)
		)
		(fp_text user "License: Apache-2.0"
			(at -0.939 5.799 90)
			(layer "F.Fab")
			(effects
				(font
					(size 0.7 0.7)
					(thickness 0.15)
				)
				(justify left bottom)
			)
		)
		(pad "1" smd roundrect
			(at -0.48 0 90)
			(size 0.59 0.64)
			(layers "F.Cu" "F.Mask" "F.Paste")
			(roundrect_rratio 0.25)
			(net 649 "VDD")
			(pintype "passive")
		)
		(pad "2" smd roundrect
			(at 0.48 0 90)
			(size 0.59 0.64)
			(layers "F.Cu" "F.Mask" "F.Paste")
			(roundrect_rratio 0.25)
			(net 417 "GND")
			(pintype "passive")
		)
	)
	(footprint "antmicro-footprints:R_0402_1005Metric"
		(layer "F.Cu")
		(at 210.425 121.35 180)
		(descr "Resistor SMD 0402")
		(tags "resistor SMD 0402")
		(property "Reference" "R60"
			(at -1.215 -2.35 0)
			(layer "F.SilkS")
			(effects
				(font
					(size 0.7 0.7)
					(thickness 0.15)
				)
				(justify right bottom)
			)
		)
		(property "Value" "R_0R_0402"
			(at -1.011843 1.772047 0)
			(layer "F.Fab")
			(hide yes)
			(effects
				(font
					(size 0.7 0.7)
					(thickness 0.15)
				)
				(justify right bottom)
			)
		)
		(property "Datasheet" "https://industrial.panasonic.com/cdbs/www-data/pdf/RDA0000/AOA0000C301.pdf"
			(at 0 0 180)
			(layer "F.Fab")
			(hide yes)
			(effects
				(font
					(size 1.27 1.27)
					(thickness 0.15)
				)
			)
		)
		(property "Description" "SMD Chip Resistor, Jumper, 0 ohm, 100 mW, 0402 [1005 Metric], Thick Film, General Purpose"
			(at 0 0 180)
			(layer "F.Fab")
			(hide yes)
			(effects
				(font
					(size 1.27 1.27)
					(thickness 0.15)
				)
			)
		)
		(property "Author" "Antmicro"
			(at 420.85 242.7 0)
			(layer "F.Fab")
			(hide yes)
			(effects
				(font
					(size 1 1)
					(thickness 0.15)
				)
			)
		)
		(property "Current" "1A"
			(at 420.85 242.7 0)
			(layer "F.Fab")
			(hide yes)
			(effects
				(font
					(size 1 1)
					(thickness 0.15)
				)
			)
		)
		(property "License" "Apache-2.0"
			(at 420.85 242.7 0)
			(layer "F.Fab")
			(hide yes)
			(effects
				(font
					(size 1 1)
					(thickness 0.15)
				)
			)
		)
		(property "MPN" "ERJ2GE0R00X"
			(at 420.85 242.7 0)
			(layer "F.Fab")
			(hide yes)
			(effects
				(font
					(size 1 1)
					(thickness 0.15)
				)
			)
		)
		(property "Manufacturer" "Panasonic"
			(at 420.85 242.7 0)
			(layer "F.Fab")
			(hide yes)
			(effects
				(font
					(size 1 1)
					(thickness 0.15)
				)
			)
		)
		(property "Public" ""
			(at 420.85 242.7 0)
			(layer "F.Fab")
			(hide yes)
			(effects
				(font
					(size 1 1)
					(thickness 0.15)
				)
			)
		)
		(property "Tolerance" "~"
			(at 420.85 242.7 0)
			(layer "F.Fab")
			(hide yes)
			(effects
				(font
					(size 1 1)
					(thickness 0.15)
				)
			)
		)
		(property "Val" "0R"
			(at 420.85 242.7 0)
			(layer "F.Fab")
			(hide yes)
			(effects
				(font
					(size 1 1)
					(thickness 0.15)
				)
			)
		)
		(sheetname "/FPGA MSS/")
		(sheetfile "fpga-mss.kicad_sch")
		(attr smd)
		(fp_rect
			(start -0.925 -0.47)
			(end 0.925 0.47)
			(stroke
				(width 0.05)
				(type default)
			)
			(fill no)
			(layer "F.CrtYd")
		)
		(fp_rect
			(start -0.5 -0.25)
			(end 0.5 0.25)
			(stroke
				(width 0.15)
				(type solid)
			)
			(fill no)
			(layer "F.Fab")
		)
		(fp_text user "License: Apache-2.0"
			(at -0.95 5.169 180)
			(layer "F.Fab")
			(effects
				(font
					(size 0.7 0.7)
					(thickness 0.15)
				)
				(justify left bottom)
			)
		)
		(fp_text user "Author: Antmicro"
			(at -0.95 4.169 180)
			(layer "F.Fab")
			(effects
				(font
					(size 0.7 0.7)
					(thickness 0.15)
				)
				(justify left bottom)
			)
		)
		(fp_text user "${REFERENCE}"
			(at -0.95 3.168 180)
			(layer "F.Fab")
			(effects
				(font
					(size 0.7 0.7)
					(thickness 0.15)
				)
				(justify left bottom)
			)
		)
		(pad "1" smd roundrect
			(at -0.48 0 180)
			(size 0.59 0.64)
			(layers "F.Cu" "F.Mask" "F.Paste")
			(roundrect_rratio 0.25)
			(net 301 "/FPGA MSS/MSS_CLK_P")
			(pintype "passive")
		)
		(pad "2" smd roundrect
			(at 0.48 0 180)
			(size 0.59 0.64)
			(layers "F.Cu" "F.Mask" "F.Paste")
			(roundrect_rratio 0.25)
			(net 10 "MSS_REFCLK_P")
			(pintype "passive")
		)
	)
	(footprint "antmicro-footprints:C_0402_1005Metric"
		(layer "F.Cu")
		(at 183.734404 153.204531 180)
		(descr "Capacitor SMD 0402")
		(tags "capacitor SMD 0402")
		(property "Reference" "C89"
			(at -1.785596 1.764531 90)
			(layer "F.SilkS")
			(effects
				(font
					(size 0.7 0.7)
					(thickness 0.15)
				)
				(justify right bottom)
			)
		)
		(property "Value" "C_470n_0402"
			(at -1.022927 2.155213 0)
			(layer "F.Fab")
			(hide yes)
			(effects
				(font
					(size 0.7 0.7)
					(thickness 0.15)
				)
				(justify right bottom)
			)
		)
		(property "Datasheet" "https://product.tdk.com/en/search/capacitor/ceramic/mlcc/info?part_no=C1005X5R1E474M050BB"
			(at 0 0 180)
			(layer "F.Fab")
			(hide yes)
			(effects
				(font
					(size 1.27 1.27)
					(thickness 0.15)
				)
			)
		)
		(property "Description" "SMD Multilayer Ceramic Capacitor, 0.47 µF, 25 V, 0402 [1005 Metric], ± 20%, X5R, C"
			(at 0 0 180)
			(layer "F.Fab")
			(hide yes)
			(effects
				(font
					(size 1.27 1.27)
					(thickness 0.15)
				)
			)
		)
		(property "Author" "Antmicro"
			(at 367.468808 306.409062 0)
			(layer "F.Fab")
			(hide yes)
			(effects
				(font
					(size 1 1)
					(thickness 0.15)
				)
			)
		)
		(property "Dielectric" ""
			(at 367.468808 306.409062 0)
			(layer "F.Fab")
			(hide yes)
			(effects
				(font
					(size 1 1)
					(thickness 0.15)
				)
			)
		)
		(property "License" "Apache-2.0"
			(at 367.468808 306.409062 0)
			(layer "F.Fab")
			(hide yes)
			(effects
				(font
					(size 1 1)
					(thickness 0.15)
				)
			)
		)
		(property "MPN" "C1005X5R1E474M050BB"
			(at 367.468808 306.409062 0)
			(layer "F.Fab")
			(hide yes)
			(effects
				(font
					(size 1 1)
					(thickness 0.15)
				)
			)
		)
		(property "Manufacturer" "TDK"
			(at 367.468808 306.409062 0)
			(layer "F.Fab")
			(hide yes)
			(effects
				(font
					(size 1 1)
					(thickness 0.15)
				)
			)
		)
		(property "Public" ""
			(at 367.468808 306.409062 0)
			(layer "F.Fab")
			(hide yes)
			(effects
				(font
					(size 1 1)
					(thickness 0.15)
				)
			)
		)
		(property "Val" "470n"
			(at 367.468808 306.409062 0)
			(layer "F.Fab")
			(hide yes)
			(effects
				(font
					(size 1 1)
					(thickness 0.15)
				)
			)
		)
		(property "Voltage" ""
			(at 367.468808 306.409062 0)
			(layer "F.Fab")
			(hide yes)
			(effects
				(font
					(size 1 1)
					(thickness 0.15)
				)
			)
		)
		(sheetname "/Supply/")
		(sheetfile "supply.kicad_sch")
		(attr smd)
		(fp_rect
			(start -0.925 -0.47)
			(end 0.925 0.47)
			(stroke
				(width 0.05)
				(type default)
			)
			(fill no)
			(layer "F.CrtYd")
		)
		(fp_line
			(start 0.504 0.248)
			(end -0.494 0.248)
			(stroke
				(width 0.15)
				(type solid)
			)
			(layer "F.Fab")
		)
		(fp_line
			(start 0.504 -0.25)
			(end 0.504 0.248)
			(stroke
				(width 0.15)
				(type solid)
			)
			(layer "F.Fab")
		)
		(fp_line
			(start -0.494 0.248)
			(end -0.494 -0.25)
			(stroke
				(width 0.15)
				(type solid)
			)
			(layer "F.Fab")
		)
		(fp_line
			(start -0.494 -0.25)
			(end 0.504 -0.25)
			(stroke
				(width 0.15)
				(type solid)
			)
			(layer "F.Fab")
		)
		(fp_text user "Author: Antmicro"
			(at -0.939 3.399 180)
			(layer "F.Fab")
			(effects
				(font
					(size 0.7 0.7)
					(thickness 0.15)
				)
				(justify left bottom)
			)
		)
		(fp_text user "License: Apache-2.0"
			(at -0.939 5.799 180)
			(layer "F.Fab")
			(effects
				(font
					(size 0.7 0.7)
					(thickness 0.15)
				)
				(justify left bottom)
			)
		)
		(fp_text user "${REFERENCE}"
			(at -0.939 4.599 180)
			(layer "F.Fab")
			(effects
				(font
					(size 0.7 0.7)
					(thickness 0.15)
				)
				(justify left bottom)
			)
		)
		(pad "1" smd roundrect
			(at -0.48 0 180)
			(size 0.59 0.64)
			(layers "F.Cu" "F.Mask" "F.Paste")
			(roundrect_rratio 0.25)
			(net 417 "GND")
			(pintype "passive")
		)
		(pad "2" smd roundrect
			(at 0.48 0 180)
			(size 0.59 0.64)
			(layers "F.Cu" "F.Mask" "F.Paste")
			(roundrect_rratio 0.25)
			(net 148 "/Supply/1V05_VCC")
			(pintype "passive")
		)
	)
)
